(kicad_pcb
	(version 20260206)
	(generator "pcbnew")
	(generator_version "10.0")
	(general
		(thickness 1.6)
		(legacy_teardrops no)
	)
	(paper "A4")
	(title_block
		(title "03242023_DA0F0TMBIJ0_F0T_Motherboard_J_brd_V01_OCP.brd")
		(comment 1 "Grand Teton / footprint 1792 of 6105 (J105), pads 1-48 of 48")
	)
	(layers
		(0 "F.Cu" signal "TOP")
		(4 "In1.Cu" signal "GND")
		(6 "In2.Cu" signal "IN1")
		(8 "In3.Cu" signal "GND1")
		(10 "In4.Cu" signal "IN2")
		(12 "In5.Cu" signal "GND2")
		(14 "In6.Cu" signal "IN3")
		(16 "In7.Cu" signal "GND3")
		(18 "In8.Cu" signal "VCC")
		(20 "In9.Cu" signal "VCC1")
		(22 "In10.Cu" signal "GND4")
		(24 "In11.Cu" signal "IN4")
		(26 "In12.Cu" signal "GND5")
		(28 "In13.Cu" signal "IN5")
		(30 "In14.Cu" signal "GND6")
		(32 "In15.Cu" signal "IN6")
		(34 "In16.Cu" signal "GND7")
		(2 "B.Cu" signal "BOTTOM")
		(9 "F.Adhes" user "F.Adhesive")
		(11 "B.Adhes" user "B.Adhesive")
		(13 "F.Paste" user "Package Geometry/Pastemask Top")
		(15 "B.Paste" user "Package Geometry/Pastemask Bottom")
		(5 "F.SilkS" user "Ref Des/Silkscreen Top")
		(7 "B.SilkS" user "Ref Des/Silkscreen Bottom")
		(1 "F.Mask" user "Board Geometry/Soldermask Top")
		(3 "B.Mask" user "Board Geometry/Soldermask Bottom")
		(17 "Dwgs.User" user "User.Drawings")
		(19 "Cmts.User" user "User.Comments")
		(21 "Eco1.User" user "User.Eco1")
		(23 "Eco2.User" user "User.Eco2")
		(25 "Edge.Cuts" user "Board Geometry/Outline")
		(27 "Margin" user)
		(31 "F.CrtYd" user "Package Geometry/Place Bound Top")
		(29 "B.CrtYd" user "Package Geometry/Place Bound Bottom")
		(35 "F.Fab" user "Ref Des/Assembly Top")
		(33 "B.Fab" user "Ref Des/Assembly Bottom")
	)
	(footprint ""
		(layer "F.Cu")
		(at 398.750028 -440.489848)
		(property "Reference" "J105"
			(at -2.99466 23.400512 0)
			(unlocked yes)
			(layer "F.SilkS")
			(effects
				(font
					(size 0.7874 0.5842)
					(thickness 0.1524)
				)
				(justify left)
			)
		)
		(property "Value" ""
			(at 0 0 0)
			(layer "F.Fab")
			(effects
				(font
					(size 1.27 1.27)
				)
			)
		)
		(duplicate_pad_numbers_are_jumpers no)
		(pad "A1" thru_hole rect
			(at 0 0 180)
			(size 0.766318 0.766318)
			(drill 0.359918)
			(layers "*.Cu" "*.Mask")
			(remove_unused_layers no)
			(net "GPU_3V3IO_RSVD4")
			(clearance 0.0508)
			(thermal_gap 0.0508)
			(padstack
				(mode front_inner_back)
				(layer "Inner"
					(shape circle)
					(size 0.766318 0.766318)
					(clearance 0.0508)
				)
				(layer "B.Cu"
					(shape rect)
					(size 0.766318 0.766318)
					(clearance 0.0508)
				)
			)
		)
		(pad "A2" thru_hole circle
			(at 1.999996 0.199898 180)
			(size 0.906272 0.906272)
			(drill 0.499872)
			(layers "*.Cu" "*.Mask")
			(remove_unused_layers no)
			(net "GND")
			(clearance 0.0508)
			(thermal_gap 0.0508)
		)
		(pad "A3" thru_hole circle
			(at 3.999992 0 180)
			(size 0.766318 0.766318)
			(drill 0.359918)
			(layers "*.Cu" "*.Mask")
			(remove_unused_layers no)
			(net "GPU_WP_HW_CTRL_ISO")
			(clearance 0.0508)
			(thermal_gap 0.0508)
		)
		(pad "A4" thru_hole circle
			(at 5.999988 0.199898 180)
			(size 0.906272 0.906272)
			(drill 0.499872)
			(layers "*.Cu" "*.Mask")
			(remove_unused_layers no)
			(net "GND")
			(clearance 0.0508)
			(thermal_gap 0.0508)
		)
		(pad "A5" thru_hole circle
			(at 7.999984 0 180)
			(size 0.766318 0.766318)
			(drill 0.359918)
			(layers "*.Cu" "*.Mask")
			(remove_unused_layers no)
			(net "GPU_3V3IO_RSVD3")
			(clearance 0.0508)
			(thermal_gap 0.0508)
		)
		(pad "A6" thru_hole circle
			(at 9.99998 0.199898 180)
			(size 0.906272 0.906272)
			(drill 0.499872)
			(layers "*.Cu" "*.Mask")
			(remove_unused_layers no)
			(net "GND")
			(clearance 0.0508)
			(thermal_gap 0.0508)
		)
		(pad "A7" thru_hole circle
			(at 11.999976 0 180)
			(size 0.766318 0.766318)
			(drill 0.359918)
			(layers "*.Cu" "*.Mask")
			(remove_unused_layers no)
			(net "GPU_3V3IO_RSVD1")
			(clearance 0.0508)
			(thermal_gap 0.0508)
		)
		(pad "A8" thru_hole circle
			(at 13.999972 0.199898 180)
			(size 0.906272 0.906272)
			(drill 0.499872)
			(layers "*.Cu" "*.Mask")
			(remove_unused_layers no)
			(net "GND")
			(clearance 0.0508)
			(thermal_gap 0.0508)
		)
		(pad "B1" thru_hole circle
			(at 0 1.199896 180)
			(size 0.906272 0.906272)
			(drill 0.499872)
			(layers "*.Cu" "*.Mask")
			(remove_unused_layers no)
			(net "GND")
			(clearance 0.0508)
			(thermal_gap 0.0508)
		)
		(pad "B3" thru_hole circle
			(at 3.999992 1.199896 180)
			(size 0.906272 0.906272)
			(drill 0.499872)
			(layers "*.Cu" "*.Mask")
			(remove_unused_layers no)
			(net "GND")
			(clearance 0.0508)
			(thermal_gap 0.0508)
		)
		(pad "B5" thru_hole circle
			(at 7.999984 1.199896 180)
			(size 0.906272 0.906272)
			(drill 0.499872)
			(layers "*.Cu" "*.Mask")
			(remove_unused_layers no)
			(net "GND")
			(clearance 0.0508)
			(thermal_gap 0.0508)
		)
		(pad "B7" thru_hole circle
			(at 11.999976 1.199896 180)
			(size 0.906272 0.906272)
			(drill 0.499872)
			(layers "*.Cu" "*.Mask")
			(remove_unused_layers no)
			(net "GND")
			(clearance 0.0508)
			(thermal_gap 0.0508)
		)
		(pad "D2" thru_hole circle
			(at 1.999996 3.800094 180)
			(size 0.906272 0.906272)
			(drill 0.499872)
			(layers "*.Cu" "*.Mask")
			(remove_unused_layers no)
			(net "GND")
			(clearance 0.0508)
			(thermal_gap 0.0508)
		)
		(pad "D4" thru_hole circle
			(at 5.999988 3.800094 180)
			(size 0.906272 0.906272)
			(drill 0.499872)
			(layers "*.Cu" "*.Mask")
			(remove_unused_layers no)
			(net "GND")
			(clearance 0.0508)
			(thermal_gap 0.0508)
		)
		(pad "D6" thru_hole circle
			(at 9.99998 3.800094 180)
			(size 0.906272 0.906272)
			(drill 0.499872)
			(layers "*.Cu" "*.Mask")
			(remove_unused_layers no)
			(net "GND")
			(clearance 0.0508)
			(thermal_gap 0.0508)
		)
		(pad "D8" thru_hole circle
			(at 13.999972 3.800094 180)
			(size 0.906272 0.906272)
			(drill 0.499872)
			(layers "*.Cu" "*.Mask")
			(remove_unused_layers no)
			(net "GND")
			(clearance 0.0508)
			(thermal_gap 0.0508)
		)
		(pad "E1" thru_hole circle
			(at 0 4.800092 180)
			(size 0.906272 0.906272)
			(drill 0.499872)
			(layers "*.Cu" "*.Mask")
			(remove_unused_layers no)
			(net "GND")
			(clearance 0.0508)
			(thermal_gap 0.0508)
		)
		(pad "E3" thru_hole circle
			(at 3.999992 4.800092 180)
			(size 0.906272 0.906272)
			(drill 0.499872)
			(layers "*.Cu" "*.Mask")
			(remove_unused_layers no)
			(net "GND")
			(clearance 0.0508)
			(thermal_gap 0.0508)
		)
		(pad "E5" thru_hole circle
			(at 7.999984 4.800092 180)
			(size 0.906272 0.906272)
			(drill 0.499872)
			(layers "*.Cu" "*.Mask")
			(remove_unused_layers no)
			(net "GND")
			(clearance 0.0508)
			(thermal_gap 0.0508)
		)
		(pad "E7" thru_hole circle
			(at 11.999976 4.800092 180)
			(size 0.906272 0.906272)
			(drill 0.499872)
			(layers "*.Cu" "*.Mask")
			(remove_unused_layers no)
			(net "GND")
			(clearance 0.0508)
			(thermal_gap 0.0508)
		)
		(pad "G2" thru_hole circle
			(at 1.999996 7.400036 180)
			(size 0.906272 0.906272)
			(drill 0.499872)
			(layers "*.Cu" "*.Mask")
			(remove_unused_layers no)
			(net "GND")
			(clearance 0.0508)
			(thermal_gap 0.0508)
		)
		(pad "G4" thru_hole circle
			(at 5.999988 7.400036 180)
			(size 0.906272 0.906272)
			(drill 0.499872)
			(layers "*.Cu" "*.Mask")
			(remove_unused_layers no)
			(net "GND")
			(clearance 0.0508)
			(thermal_gap 0.0508)
		)
		(pad "G6" thru_hole circle
			(at 9.99998 7.400036 180)
			(size 0.906272 0.906272)
			(drill 0.499872)
			(layers "*.Cu" "*.Mask")
			(remove_unused_layers no)
			(net "GND")
			(clearance 0.0508)
			(thermal_gap 0.0508)
		)
		(pad "G8" thru_hole circle
			(at 13.999972 7.400036 180)
			(size 0.906272 0.906272)
			(drill 0.499872)
			(layers "*.Cu" "*.Mask")
			(remove_unused_layers no)
			(net "GND")
			(clearance 0.0508)
			(thermal_gap 0.0508)
		)
		(pad "H1" thru_hole circle
			(at 0 8.400034 180)
			(size 0.906272 0.906272)
			(drill 0.499872)
			(layers "*.Cu" "*.Mask")
			(remove_unused_layers no)
			(net "GND")
			(clearance 0.0508)
			(thermal_gap 0.0508)
		)
		(pad "H3" thru_hole circle
			(at 3.999992 8.400034 180)
			(size 0.906272 0.906272)
			(drill 0.499872)
			(layers "*.Cu" "*.Mask")
			(remove_unused_layers no)
			(net "GND")
			(clearance 0.0508)
			(thermal_gap 0.0508)
		)
		(pad "H5" thru_hole circle
			(at 7.999984 8.400034 180)
			(size 0.906272 0.906272)
			(drill 0.499872)
			(layers "*.Cu" "*.Mask")
			(remove_unused_layers no)
			(net "GND")
			(clearance 0.0508)
			(thermal_gap 0.0508)
		)
		(pad "H7" thru_hole circle
			(at 11.999976 8.400034 180)
			(size 0.906272 0.906272)
			(drill 0.499872)
			(layers "*.Cu" "*.Mask")
			(remove_unused_layers no)
			(net "GND")
			(clearance 0.0508)
			(thermal_gap 0.0508)
		)
		(pad "J2" thru_hole circle
			(at 1.999996 10.999978 180)
			(size 0.906272 0.906272)
			(drill 0.499872)
			(layers "*.Cu" "*.Mask")
			(remove_unused_layers no)
			(net "GND")
			(clearance 0.0508)
			(thermal_gap 0.0508)
		)
		(pad "J4" thru_hole circle
			(at 5.999988 10.999978 180)
			(size 0.906272 0.906272)
			(drill 0.499872)
			(layers "*.Cu" "*.Mask")
			(remove_unused_layers no)
			(net "GND")
			(clearance 0.0508)
			(thermal_gap 0.0508)
		)
		(pad "J6" thru_hole circle
			(at 9.99998 10.999978 180)
			(size 0.906272 0.906272)
			(drill 0.499872)
			(layers "*.Cu" "*.Mask")
			(remove_unused_layers no)
			(net "GND")
			(clearance 0.0508)
			(thermal_gap 0.0508)
		)
		(pad "J8" thru_hole circle
			(at 13.999972 10.999978 180)
			(size 0.906272 0.906272)
			(drill 0.499872)
			(layers "*.Cu" "*.Mask")
			(remove_unused_layers no)
			(net "GND")
			(clearance 0.0508)
			(thermal_gap 0.0508)
		)
		(pad "K1" thru_hole circle
			(at 0 11.999976 180)
			(size 0.906272 0.906272)
			(drill 0.499872)
			(layers "*.Cu" "*.Mask")
			(remove_unused_layers no)
			(net "GND")
			(clearance 0.0508)
			(thermal_gap 0.0508)
		)
		(pad "K3" thru_hole circle
			(at 3.999992 11.999976 180)
			(size 0.906272 0.906272)
			(drill 0.499872)
			(layers "*.Cu" "*.Mask")
			(remove_unused_layers no)
			(net "GND")
			(clearance 0.0508)
			(thermal_gap 0.0508)
		)
		(pad "K5" thru_hole circle
			(at 7.999984 11.999976 180)
			(size 0.906272 0.906272)
			(drill 0.499872)
			(layers "*.Cu" "*.Mask")
			(remove_unused_layers no)
			(net "GND")
			(clearance 0.0508)
			(thermal_gap 0.0508)
		)
		(pad "K7" thru_hole circle
			(at 11.999976 11.999976 180)
			(size 0.906272 0.906272)
			(drill 0.499872)
			(layers "*.Cu" "*.Mask")
			(remove_unused_layers no)
			(net "GND")
			(clearance 0.0508)
			(thermal_gap 0.0508)
		)
		(pad "M2" thru_hole circle
			(at 1.999996 14.59992 180)
			(size 0.906272 0.906272)
			(drill 0.499872)
			(layers "*.Cu" "*.Mask")
			(remove_unused_layers no)
			(net "GND")
			(clearance 0.0508)
			(thermal_gap 0.0508)
		)
		(pad "M4" thru_hole circle
			(at 5.999988 14.59992 180)
			(size 0.906272 0.906272)
			(drill 0.499872)
			(layers "*.Cu" "*.Mask")
			(remove_unused_layers no)
			(net "GND")
			(clearance 0.0508)
			(thermal_gap 0.0508)
		)
		(pad "M6" thru_hole circle
			(at 9.99998 14.59992 180)
			(size 0.906272 0.906272)
			(drill 0.499872)
			(layers "*.Cu" "*.Mask")
			(remove_unused_layers no)
			(net "GND")
			(clearance 0.0508)
			(thermal_gap 0.0508)
		)
		(pad "M8" thru_hole circle
			(at 13.999972 14.59992 180)
			(size 0.906272 0.906272)
			(drill 0.499872)
			(layers "*.Cu" "*.Mask")
			(remove_unused_layers no)
			(net "GND")
			(clearance 0.0508)
			(thermal_gap 0.0508)
		)
		(pad "N1" thru_hole circle
			(at 0 15.599918 180)
			(size 0.906272 0.906272)
			(drill 0.499872)
			(layers "*.Cu" "*.Mask")
			(remove_unused_layers no)
			(net "GND")
			(clearance 0.0508)
			(thermal_gap 0.0508)
		)
		(pad "N2" thru_hole circle
			(at 1.999996 15.80007 180)
			(size 0.766318 0.766318)
			(drill 0.359918)
			(layers "*.Cu" "*.Mask")
			(remove_unused_layers no)
			(net "FM_SWB_PWR_EN_R_BUF")
			(clearance 0.0508)
			(thermal_gap 0.0508)
		)
		(pad "N3" thru_hole circle
			(at 3.999992 15.599918 180)
			(size 0.906272 0.906272)
			(drill 0.499872)
			(layers "*.Cu" "*.Mask")
			(remove_unused_layers no)
			(net "GND")
			(clearance 0.0508)
			(thermal_gap 0.0508)
		)
		(pad "N4" thru_hole circle
			(at 5.999988 15.80007 180)
			(size 0.766318 0.766318)
			(drill 0.359918)
			(layers "*.Cu" "*.Mask")
			(remove_unused_layers no)
			(net "FM_SWB_BIC_READY_N")
			(clearance 0.0508)
			(thermal_gap 0.0508)
		)
		(pad "N5" thru_hole circle
			(at 7.999984 15.599918 180)
			(size 0.906272 0.906272)
			(drill 0.499872)
			(layers "*.Cu" "*.Mask")
			(remove_unused_layers no)
			(net "GND")
			(clearance 0.0508)
			(thermal_gap 0.0508)
		)
		(pad "N6" thru_hole circle
			(at 9.99998 15.80007 180)
			(size 0.766318 0.766318)
			(drill 0.359918)
			(layers "*.Cu" "*.Mask")
			(remove_unused_layers no)
			(net "RST_SWB_BIC_BUF_N")
			(clearance 0.0508)
			(thermal_gap 0.0508)
		)
		(pad "N7" thru_hole circle
			(at 11.999976 15.599918 180)
			(size 0.906272 0.906272)
			(drill 0.499872)
			(layers "*.Cu" "*.Mask")
			(remove_unused_layers no)
			(net "GND")
			(clearance 0.0508)
			(thermal_gap 0.0508)
		)
		(pad "N8" thru_hole circle
			(at 13.999972 15.80007 180)
			(size 0.766318 0.766318)
			(drill 0.359918)
			(layers "*.Cu" "*.Mask")
			(remove_unused_layers no)
			(net "RST_BMC_FROM_SWB_N")
			(clearance 0.0508)
			(thermal_gap 0.0508)
		)
	)
)
